(kicad_pcb
	(version 20241229)
	(generator "pcbnew")
	(generator_version "9.0")
	(general
		(thickness 1.63)
		(legacy_teardrops no)
	)
	(paper "A4")
	(title_block
		(title "CM4 Baseboard")
		(date "2026-01-05")
		(rev "1.1.1")
		(company "Antmicro Ltd")
		(comment 1 "www.antmicro.com")
		(comment 9 "footprints 357-360 of 506")
	)
	(layers
		(0 "F.Cu" signal)
		(4 "In1.Cu" power)
		(6 "In2.Cu" power)
		(8 "In3.Cu" signal)
		(10 "In4.Cu" signal)
		(2 "B.Cu" signal)
		(9 "F.Adhes" user "F.Adhesive")
		(11 "B.Adhes" user "B.Adhesive")
		(13 "F.Paste" user)
		(15 "B.Paste" user)
		(5 "F.SilkS" user "F.Silkscreen")
		(7 "B.SilkS" user "B.Silkscreen")
		(1 "F.Mask" user)
		(3 "B.Mask" user)
		(17 "Dwgs.User" user "User.Drawings")
		(19 "Cmts.User" user "User.Comments")
		(21 "Eco1.User" user "User.Eco1")
		(23 "Eco2.User" user "User.Eco2")
		(25 "Edge.Cuts" user)
		(27 "Margin" user)
		(31 "F.CrtYd" user "F.Courtyard")
		(29 "B.CrtYd" user "B.Courtyard")
		(35 "F.Fab" user)
		(33 "B.Fab" user)
	)
	(footprint "antmicro-footprints:Spacer_Drill3.7mm_H2mm_9774020151R"
		(layer "B.Cu")
		(at 68.117962 151.7415 180)
		(descr "Spacer M=3 h=2mm fi=5.1mm")
		(property "Reference" "H701"
			(at 0 3.2 0)
			(layer "B.SilkS")
			(effects
				(font
					(size 0.7 0.7)
					(thickness 0.15)
				)
				(justify left bottom mirror)
			)
		)
		(property "Value" "Spacer_Drill3.7mm_H2mm_9774020151R"
			(at 0 -4 0)
			(layer "B.Fab")
			(effects
				(font
					(size 0.7 0.7)
					(thickness 0.15)
				)
				(justify left bottom mirror)
			)
		)
		(property "Datasheet" "https://www.we-online.com/components/products/datasheet/9774020151R.pdf"
			(at 0 0 180)
			(layer "B.Fab")
			(hide yes)
			(effects
				(font
					(size 1.27 1.27)
					(thickness 0.15)
				)
			)
		)
		(property "Manufacturer" "Würth Elektronik"
			(at 0 0 180)
			(unlocked yes)
			(layer "B.Fab")
			(hide yes)
			(effects
				(font
					(size 1 1)
					(thickness 0.15)
				)
				(justify mirror)
			)
		)
		(property "MPN" "9774020151R"
			(at 0 0 180)
			(unlocked yes)
			(layer "B.Fab")
			(hide yes)
			(effects
				(font
					(size 1 1)
					(thickness 0.15)
				)
				(justify mirror)
			)
		)
		(property "Author" "Antmicro"
			(at 0 0 180)
			(unlocked yes)
			(layer "B.Fab")
			(hide yes)
			(effects
				(font
					(size 1 1)
					(thickness 0.15)
				)
				(justify mirror)
			)
		)
		(property "License" "Apache-2.0"
			(at 0 0 180)
			(unlocked yes)
			(layer "B.Fab")
			(hide yes)
			(effects
				(font
					(size 1 1)
					(thickness 0.15)
				)
				(justify mirror)
			)
		)
		(sheetname "/Display/")
		(sheetfile "display.kicad_sch")
		(solder_paste_margin_ratio -1)
		(attr smd)
		(fp_circle
			(center 0 0)
			(end 3.05 0)
			(stroke
				(width 0.05)
				(type solid)
			)
			(fill no)
			(layer "B.CrtYd")
		)
		(fp_circle
			(center 0 0)
			(end 2.6 0)
			(stroke
				(width 0.15)
				(type solid)
			)
			(fill no)
			(layer "B.Fab")
		)
		(fp_text user "Author: Antmicro"
			(at -9.6 -7.7 0)
			(layer "B.Fab")
			(effects
				(font
					(size 0.7 0.7)
					(thickness 0.15)
				)
				(justify left bottom mirror)
			)
		)
		(fp_text user "License: Apache-2.0"
			(at -9.6 -8.9 0)
			(layer "B.Fab")
			(effects
				(font
					(size 0.7 0.7)
					(thickness 0.15)
				)
				(justify left bottom mirror)
			)
		)
		(fp_text user "${REFERENCE}"
			(at -9.6 -6.5 0)
			(layer "B.Fab")
			(effects
				(font
					(size 0.7 0.7)
					(thickness 0.15)
				)
				(justify left bottom mirror)
			)
		)
		(pad "" smd custom
			(at -1.7 -1.7 90)
			(size 0.62 0.62)
			(layers "B.Paste")
			(thermal_bridge_angle 90)
			(options
				(clearance outline)
				(anchor circle)
			)
			(primitives
				(gr_arc
					(start 1.266786 0.24747)
					(mid 0.285453 -0.29439)
					(end -0.250195 -1.279127)
					(width 0.2)
				)
				(gr_arc
					(start 1.259603 0.339191)
					(mid 0.218448 -0.232561)
					(end -0.34334 -1.279127)
					(width 0.2)
				)
				(gr_arc
					(start 1.255279 0.431435)
					(mid 0.152481 -0.169693)
					(end -0.436309 -1.279127)
					(width 0.2)
				)
				(gr_arc
					(start 1.253811 0.524161)
					(mid 0.087542 -0.105784)
					(end -0.529126 -1.279127)
					(width 0.2)
				)
				(gr_arc
					(start 1.275473 0.621136)
					(mid 0.0309 -0.033527)
					(end -0.621807 -1.279127)
					(width 0.2)
				)
				(gr_arc
					(start 1.263664 0.711602)
					(mid -0.037759 0.026651)
					(end -0.71437 -1.279127)
					(width 0.2)
				)
				(gr_arc
					(start 1.253435 0.802342)
					(mid -0.105837 0.087395)
					(end -0.806826 -1.279127)
					(width 0.2)
				)
				(gr_arc
					(start 1.267475 0.897258)
					(mid -0.165236 0.156885)
					(end -0.899187 -1.279127)
					(width 0.2)
				)
				(gr_arc
					(start 1.270645 0.990112)
					(mid -0.228522 0.222449)
					(end -0.991463 -1.279127)
					(width 0.2)
				)
				(gr_arc
					(start 1.266278 1.081674)
					(mid -0.294507 0.285313)
					(end -1.083663 -1.279127)
					(width 0.2)
				)
				(gr_line
					(start 1.279127 0.250195)
					(end 1.279127 1.083663)
					(width 0.2)
				)
				(gr_line
					(start -0.250195 -1.279127)
					(end -1.083663 -1.279127)
					(width 0.2)
				)
			)
		)
		(pad "" smd custom
			(at -1.7 1.7 180)
			(size 0.62 0.62)
			(layers "B.Paste")
			(thermal_bridge_angle 90)
			(options
				(clearance outline)
				(anchor circle)
			)
			(primitives
				(gr_arc
					(start 1.266786 0.24747)
					(mid 0.285453 -0.29439)
					(end -0.250195 -1.279127)
					(width 0.2)
				)
				(gr_arc
					(start 1.259603 0.339191)
					(mid 0.218448 -0.232561)
					(end -0.34334 -1.279127)
					(width 0.2)
				)
				(gr_arc
					(start 1.255279 0.431435)
					(mid 0.152481 -0.169693)
					(end -0.436309 -1.279127)
					(width 0.2)
				)
				(gr_arc
					(start 1.253811 0.524161)
					(mid 0.087542 -0.105784)
					(end -0.529126 -1.279127)
					(width 0.2)
				)
				(gr_arc
					(start 1.275473 0.621136)
					(mid 0.0309 -0.033527)
					(end -0.621807 -1.279127)
					(width 0.2)
				)
				(gr_arc
					(start 1.263664 0.711602)
					(mid -0.037759 0.026651)
					(end -0.71437 -1.279127)
					(width 0.2)
				)
				(gr_arc
					(start 1.253435 0.802342)
					(mid -0.105837 0.087395)
					(end -0.806826 -1.279127)
					(width 0.2)
				)
				(gr_arc
					(start 1.267475 0.897258)
					(mid -0.165236 0.156885)
					(end -0.899187 -1.279127)
					(width 0.2)
				)
				(gr_arc
					(start 1.270645 0.990112)
					(mid -0.228522 0.222449)
					(end -0.991463 -1.279127)
					(width 0.2)
				)
				(gr_arc
					(start 1.266278 1.081674)
					(mid -0.294507 0.285313)
					(end -1.083663 -1.279127)
					(width 0.2)
				)
				(gr_line
					(start 1.279127 0.250195)
					(end 1.279127 1.083663)
					(width 0.2)
				)
				(gr_line
					(start -0.250195 -1.279127)
					(end -1.083663 -1.279127)
					(width 0.2)
				)
			)
		)
		(pad "" smd custom
			(at 1.7 -1.7)
			(size 0.62 0.62)
			(layers "B.Paste")
			(thermal_bridge_angle 90)
			(options
				(clearance outline)
				(anchor circle)
			)
			(primitives
				(gr_arc
					(start 1.266786 0.24747)
					(mid 0.285453 -0.29439)
					(end -0.250195 -1.279127)
					(width 0.2)
				)
				(gr_arc
					(start 1.259603 0.339191)
					(mid 0.218448 -0.232561)
					(end -0.34334 -1.279127)
					(width 0.2)
				)
				(gr_arc
					(start 1.255279 0.431435)
					(mid 0.152481 -0.169693)
					(end -0.436309 -1.279127)
					(width 0.2)
				)
				(gr_arc
					(start 1.253811 0.524161)
					(mid 0.087542 -0.105784)
					(end -0.529126 -1.279127)
					(width 0.2)
				)
				(gr_arc
					(start 1.275473 0.621136)
					(mid 0.0309 -0.033527)
					(end -0.621807 -1.279127)
					(width 0.2)
				)
				(gr_arc
					(start 1.263664 0.711602)
					(mid -0.037759 0.026651)
					(end -0.71437 -1.279127)
					(width 0.2)
				)
				(gr_arc
					(start 1.253435 0.802342)
					(mid -0.105837 0.087395)
					(end -0.806826 -1.279127)
					(width 0.2)
				)
				(gr_arc
					(start 1.267475 0.897258)
					(mid -0.165236 0.156885)
					(end -0.899187 -1.279127)
					(width 0.2)
				)
				(gr_arc
					(start 1.270645 0.990112)
					(mid -0.228522 0.222449)
					(end -0.991463 -1.279127)
					(width 0.2)
				)
				(gr_arc
					(start 1.266278 1.081674)
					(mid -0.294507 0.285313)
					(end -1.083663 -1.279127)
					(width 0.2)
				)
				(gr_line
					(start 1.279127 0.250195)
					(end 1.279127 1.083663)
					(width 0.2)
				)
				(gr_line
					(start -0.250195 -1.279127)
					(end -1.083663 -1.279127)
					(width 0.2)
				)
			)
		)
		(pad "" smd custom
			(at 1.7 1.7 270)
			(size 0.62 0.62)
			(layers "B.Paste")
			(thermal_bridge_angle 90)
			(options
				(clearance outline)
				(anchor circle)
			)
			(primitives
				(gr_arc
					(start 1.266786 0.24747)
					(mid 0.285453 -0.29439)
					(end -0.250195 -1.279127)
					(width 0.2)
				)
				(gr_arc
					(start 1.259603 0.339191)
					(mid 0.218448 -0.232561)
					(end -0.34334 -1.279127)
					(width 0.2)
				)
				(gr_arc
					(start 1.255279 0.431435)
					(mid 0.152481 -0.169693)
					(end -0.436309 -1.279127)
					(width 0.2)
				)
				(gr_arc
					(start 1.253811 0.524161)
					(mid 0.087542 -0.105784)
					(end -0.529126 -1.279127)
					(width 0.2)
				)
				(gr_arc
					(start 1.275473 0.621136)
					(mid 0.0309 -0.033527)
					(end -0.621807 -1.279127)
					(width 0.2)
				)
				(gr_arc
					(start 1.263664 0.711602)
					(mid -0.037759 0.026651)
					(end -0.71437 -1.279127)
					(width 0.2)
				)
				(gr_arc
					(start 1.253435 0.802342)
					(mid -0.105837 0.087395)
					(end -0.806826 -1.279127)
					(width 0.2)
				)
				(gr_arc
					(start 1.267475 0.897258)
					(mid -0.165236 0.156885)
					(end -0.899187 -1.279127)
					(width 0.2)
				)
				(gr_arc
					(start 1.270645 0.990112)
					(mid -0.228522 0.222449)
					(end -0.991463 -1.279127)
					(width 0.2)
				)
				(gr_arc
					(start 1.266278 1.081674)
					(mid -0.294507 0.285313)
					(end -1.083663 -1.279127)
					(width 0.2)
				)
				(gr_line
					(start 1.279127 0.250195)
					(end 1.279127 1.083663)
					(width 0.2)
				)
				(gr_line
					(start -0.250195 -1.279127)
					(end -1.083663 -1.279127)
					(width 0.2)
				)
			)
		)
		(pad "1" thru_hole circle
			(at 0 0 180)
			(size 6 6)
			(drill 3.7)
			(layers "*.Cu" "*.Mask")
			(remove_unused_layers no)
			(net 3 "GND")
			(pintype "passive")
		)
	)
	(footprint "antmicro-footprints:C_0805_2012Metric"
		(layer "B.Cu")
		(at 65.817962 158.1165 90)
		(descr "Capacitor SMD 0805")
		(tags "capacitor SMD 0805")
		(property "Reference" "C318"
			(at 0.75 3.92 90)
			(layer "B.SilkS")
			(effects
				(font
					(size 0.7 0.7)
					(thickness 0.15)
				)
				(justify right bottom mirror)
			)
		)
		(property "Value" "C_22u_25V_0805"
			(at -2.055717 -1.963152 90)
			(layer "B.Fab")
			(effects
				(font
					(size 0.7 0.7)
					(thickness 0.15)
				)
				(justify right bottom mirror)
			)
		)
		(property "Datasheet" "https://product.samsungsem.com/mlcc/CL21A226MAYNNN.do"
			(at 0 0 90)
			(layer "B.Fab")
			(hide yes)
			(effects
				(font
					(size 1.27 1.27)
					(thickness 0.15)
				)
			)
		)
		(property "Manufacturer" "Samsung Electro-Mechanics"
			(at 0 0 90)
			(unlocked yes)
			(layer "B.Fab")
			(hide yes)
			(effects
				(font
					(size 1 1)
					(thickness 0.15)
				)
				(justify mirror)
			)
		)
		(property "MPN" "CL21A226MAYNNNE"
			(at 0 0 90)
			(unlocked yes)
			(layer "B.Fab")
			(hide yes)
			(effects
				(font
					(size 1 1)
					(thickness 0.15)
				)
				(justify mirror)
			)
		)
		(property "Val" "22u"
			(at 0 0 90)
			(unlocked yes)
			(layer "B.Fab")
			(hide yes)
			(effects
				(font
					(size 1 1)
					(thickness 0.15)
				)
				(justify mirror)
			)
		)
		(property "License" "Apache-2.0"
			(at 0 0 90)
			(unlocked yes)
			(layer "B.Fab")
			(hide yes)
			(effects
				(font
					(size 1 1)
					(thickness 0.15)
				)
				(justify mirror)
			)
		)
		(property "Author" "Antmicro"
			(at 0 0 90)
			(unlocked yes)
			(layer "B.Fab")
			(hide yes)
			(effects
				(font
					(size 1 1)
					(thickness 0.15)
				)
				(justify mirror)
			)
		)
		(property "Voltage" "25V"
			(at 0 0 90)
			(unlocked yes)
			(layer "B.Fab")
			(hide yes)
			(effects
				(font
					(size 1 1)
					(thickness 0.15)
				)
				(justify mirror)
			)
		)
		(property "Dielectric" "X5R"
			(at 0 0 90)
			(unlocked yes)
			(layer "B.Fab")
			(hide yes)
			(effects
				(font
					(size 1 1)
					(thickness 0.15)
				)
				(justify mirror)
			)
		)
		(property "Public" "False"
			(at 0 0 90)
			(unlocked yes)
			(layer "B.Fab")
			(hide yes)
			(effects
				(font
					(size 1 1)
					(thickness 0.15)
				)
				(justify mirror)
			)
		)
		(sheetname "/Supply/")
		(sheetfile "supply.kicad_sch")
		(attr smd)
		(fp_line
			(start -0.3 -0.7)
			(end 0.3 -0.7)
			(stroke
				(width 0.15)
				(type solid)
			)
			(layer "B.SilkS")
		)
		(fp_line
			(start -0.3 0.7)
			(end 0.3 0.7)
			(stroke
				(width 0.15)
				(type solid)
			)
			(layer "B.SilkS")
		)
		(fp_rect
			(start 1.95 0.9)
			(end -1.95 -0.9)
			(stroke
				(width 0.05)
				(type default)
			)
			(fill no)
			(layer "B.CrtYd")
		)
		(fp_rect
			(start -0.95 0.675)
			(end 0.95 -0.675)
			(stroke
				(width 0.15)
				(type solid)
			)
			(fill no)
			(layer "B.Fab")
		)
		(fp_text user "Author: Antmicro"
			(at -1.9 -5.947 270)
			(layer "B.Fab")
			(effects
				(font
					(size 0.7 0.7)
					(thickness 0.15)
				)
				(justify left bottom mirror)
			)
		)
		(fp_text user "${REFERENCE}"
			(at -1.9 -3.947 270)
			(layer "B.Fab")
			(effects
				(font
					(size 0.7 0.7)
					(thickness 0.15)
				)
				(justify left bottom mirror)
			)
		)
		(fp_text user "License: Apache-2.0"
			(at -1.9 -4.947 270)
			(layer "B.Fab")
			(effects
				(font
					(size 0.7 0.7)
					(thickness 0.15)
				)
				(justify left bottom mirror)
			)
		)
		(pad "1" smd roundrect
			(at -1.1 0 90)
			(size 1.2 1.3)
			(layers "B.Cu" "B.Mask" "B.Paste")
			(roundrect_rratio 0.25)
			(net 77 "/Supply/OUT_5V")
			(pintype "passive")
		)
		(pad "2" smd roundrect
			(at 1.1 0 90)
			(size 1.2 1.3)
			(layers "B.Cu" "B.Mask" "B.Paste")
			(roundrect_rratio 0.25)
			(net 3 "GND")
			(pintype "passive")
		)
	)
	(footprint "antmicro-footprints:R_0402_1005Metric"
		(layer "B.Cu")
		(at 80.342962 135.5415 90)
		(descr "Resistor SMD 0402")
		(tags "resistor SMD 0402")
		(property "Reference" "R907"
			(at -2.845 -0.335 90)
			(layer "B.SilkS")
			(effects
				(font
					(size 0.7 0.7)
					(thickness 0.15)
				)
				(justify right bottom mirror)
			)
		)
		(property "Value" "R_2k2_0402"
			(at -1.011843 -1.772047 90)
			(layer "B.Fab")
			(effects
				(font
					(size 0.7 0.7)
					(thickness 0.15)
				)
				(justify right bottom mirror)
			)
		)
		(property "Datasheet" "https://www.bourns.com/docs/product-datasheets/cr.pdf"
			(at 0 0 90)
			(layer "B.Fab")
			(hide yes)
			(effects
				(font
					(size 1.27 1.27)
					(thickness 0.15)
				)
			)
		)
		(property "Manufacturer" "Bourns"
			(at 0 0 90)
			(unlocked yes)
			(layer "B.Fab")
			(hide yes)
			(effects
				(font
					(size 1 1)
					(thickness 0.15)
				)
				(justify mirror)
			)
		)
		(property "MPN" "CR0402-FX-2201GLF"
			(at 0 0 90)
			(unlocked yes)
			(layer "B.Fab")
			(hide yes)
			(effects
				(font
					(size 1 1)
					(thickness 0.15)
				)
				(justify mirror)
			)
		)
		(property "Val" "2k2"
			(at 0 0 90)
			(unlocked yes)
			(layer "B.Fab")
			(hide yes)
			(effects
				(font
					(size 1 1)
					(thickness 0.15)
				)
				(justify mirror)
			)
		)
		(property "License" "Apache-2.0"
			(at 0 0 90)
			(unlocked yes)
			(layer "B.Fab")
			(hide yes)
			(effects
				(font
					(size 1 1)
					(thickness 0.15)
				)
				(justify mirror)
			)
		)
		(property "Author" "Antmicro"
			(at 0 0 90)
			(unlocked yes)
			(layer "B.Fab")
			(hide yes)
			(effects
				(font
					(size 1 1)
					(thickness 0.15)
				)
				(justify mirror)
			)
		)
		(property "Tolerance" "1%"
			(at 0 0 90)
			(unlocked yes)
			(layer "B.Fab")
			(hide yes)
			(effects
				(font
					(size 1 1)
					(thickness 0.15)
				)
				(justify mirror)
			)
		)
		(sheetname "/USB/")
		(sheetfile "usb.kicad_sch")
		(attr smd)
		(fp_rect
			(start -0.925 0.47)
			(end 0.925 -0.47)
			(stroke
				(width 0.05)
				(type default)
			)
			(fill no)
			(layer "B.CrtYd")
		)
		(fp_rect
			(start -0.5 0.25)
			(end 0.5 -0.25)
			(stroke
				(width 0.15)
				(type solid)
			)
			(fill no)
			(layer "B.Fab")
		)
		(fp_text user "${REFERENCE}"
			(at -0.95 -3.168 270)
			(layer "B.Fab")
			(effects
				(font
					(size 0.7 0.7)
					(thickness 0.15)
				)
				(justify left bottom mirror)
			)
		)
		(fp_text user "Author: Antmicro"
			(at -0.95 -4.169 270)
			(layer "B.Fab")
			(effects
				(font
					(size 0.7 0.7)
					(thickness 0.15)
				)
				(justify left bottom mirror)
			)
		)
		(fp_text user "License: Apache-2.0"
			(at -0.95 -5.169 270)
			(layer "B.Fab")
			(effects
				(font
					(size 0.7 0.7)
					(thickness 0.15)
				)
				(justify left bottom mirror)
			)
		)
		(pad "1" smd roundrect
			(at -0.48 0 90)
			(size 0.59 0.64)
			(layers "B.Cu" "B.Mask" "B.Paste")
			(roundrect_rratio 0.25)
			(net 377 "Net-(U902-DO)")
			(pintype "passive")
		)
		(pad "2" smd roundrect
			(at 0.48 0 90)
			(size 0.59 0.64)
			(layers "B.Cu" "B.Mask" "B.Paste")
			(roundrect_rratio 0.25)
			(net 281 "/USB/EEDATA")
			(pintype "passive")
		)
	)
	(footprint "antmicro-footprints:TP_SMD_0.75mm"
		(layer "B.Cu")
		(at 55.27 152.28 -90)
		(property "Reference" "TP304"
			(at -1.01 -2.43 180)
			(layer "B.SilkS")
			(effects
				(font
					(size 0.7 0.7)
					(thickness 0.15)
				)
				(justify left bottom mirror)
			)
		)
		(property "Value" "TP_0.75mm_SMD"
			(at 0 -1.2 90)
			(layer "B.Fab")
			(effects
				(font
					(size 0.7 0.7)
					(thickness 0.15)
				)
				(justify left bottom mirror)
			)
		)
		(property "Author" "Antmicro"
			(at 0 0 270)
			(unlocked yes)
			(layer "B.Fab")
			(hide yes)
			(effects
				(font
					(size 1 1)
					(thickness 0.15)
				)
				(justify mirror)
			)
		)
		(property "License" "Apache-2.0"
			(at 0 0 270)
			(unlocked yes)
			(layer "B.Fab")
			(hide yes)
			(effects
				(font
					(size 1 1)
					(thickness 0.15)
				)
				(justify mirror)
			)
		)
		(property "MPN" ""
			(at 0 0 270)
			(unlocked yes)
			(layer "B.Fab")
			(hide yes)
			(effects
				(font
					(size 1 1)
					(thickness 0.15)
				)
				(justify mirror)
			)
		)
		(property "Manufacturer" ""
			(at 0 0 270)
			(unlocked yes)
			(layer "B.Fab")
			(hide yes)
			(effects
				(font
					(size 1 1)
					(thickness 0.15)
				)
				(justify mirror)
			)
		)
		(sheetname "/Supply/")
		(sheetfile "supply.kicad_sch")
		(attr exclude_from_pos_files exclude_from_bom)
		(fp_circle
			(center 0 0)
			(end 0.475 0)
			(stroke
				(width 0.05)
				(type default)
			)
			(fill no)
			(layer "B.CrtYd")
		)
		(fp_text user "License: Apache-2.0"
			(at -0.4 -5.101 90)
			(layer "B.Fab")
			(effects
				(font
					(size 0.7 0.7)
					(thickness 0.15)
				)
				(justify left bottom mirror)
			)
		)
		(fp_text user "${REFERENCE}"
			(at -0.4 -2.7 90)
			(layer "B.Fab")
			(effects
				(font
					(size 0.7 0.7)
					(thickness 0.15)
				)
				(justify left bottom mirror)
			)
		)
		(fp_text user "Author: Antmicro"
			(at -0.4 -3.901 90)
			(layer "B.Fab")
			(effects
				(font
					(size 0.7 0.7)
					(thickness 0.15)
				)
				(justify left bottom mirror)
			)
		)
		(pad "1" smd circle
			(at 0 0 270)
			(size 0.75 0.75)
			(layers "B.Cu" "B.Mask")
			(net 352 "Net-(U303-PG)")
			(pinfunction "1")
			(pintype "passive")
		)
	)
)
